#ISCELL
  mstr_misc dns *
  *
#ISCELL
  mstr_symbols cad_note *
  *
#ISCELL
  mstr_symbols design_note *
  *
#ISCELL
  mstr_symbols intel_corp_bpage *
  *
#ISCELL
  mstr_standard offpage *
  page181_i1
#ISCELL
  mstr_standard offpage *
  page181_i10
#ISCELL
  mstr_standard offpage *
  page181_i100
#ISCELL
  mstr_standard offpage *
  page181_i101
#ISCELL
  mstr_standard offpage *
  page181_i102
#ISCELL
  mstr_standard offpage *
  page181_i103
#ISCELL
  mstr_symbols gnd *
  page181_i104
#ISCELL
  mstr_symbols p3v3_stby *
  page181_i105
#CELL
  mstr_conn conn8_h62179001 *
  page181_i106
#ISCELL
  mstr_standard tap *
  page181_i107
#ISCELL
  mstr_standard tap *
  page181_i108
#ISCELL
  mstr_standard offpage *
  page181_i109
#ISCELL
  mstr_standard offpage *
  page181_i11
#ISCELL
  mstr_standard offpage *
  page181_i110
#ISCELL
  mstr_standard offpage *
  page181_i111
#ISCELL
  mstr_standard tap *
  page181_i112
#ISCELL
  mstr_standard tap *
  page181_i113
#ISCELL
  mstr_standard tap *
  page181_i114
#ISCELL
  mstr_standard tap *
  page181_i115
#ISCELL
  mstr_standard tap *
  page181_i116
#ISCELL
  mstr_standard tap *
  page181_i117
#ISCELL
  mstr_standard offpage *
  page181_i118
#ISCELL
  mstr_standard offpage *
  page181_i119
#ISCELL
  mstr_standard offpage *
  page181_i12
#ISCELL
  mstr_standard offpage *
  page181_i120
#ISCELL
  mstr_standard offpage *
  page181_i121
#ISCELL
  mstr_standard offpage *
  page181_i122
#ISCELL
  mstr_standard offpage *
  page181_i123
#ISCELL
  mstr_standard offpage *
  page181_i124
#ISCELL
  mstr_standard offpage *
  page181_i125
#ISCELL
  mstr_standard offpage *
  page181_i126
#ISCELL
  mstr_standard offpage *
  page181_i127
#ISCELL
  mstr_standard offpage *
  page181_i128
#ISCELL
  mstr_standard offpage *
  page181_i129
#ISCELL
  mstr_standard offpage *
  page181_i13
#ISCELL
  mstr_standard offpage *
  page181_i130
#ISCELL
  mstr_standard offpage *
  page181_i131
#ISCELL
  mstr_standard tap *
  page181_i132
#CELL
  w_hdl dm-fci-conn76-8r-gp-u-01 *
  page181_i134
#ISCELL
  mstr_symbols gnd *
  page181_i136
#CELL
  mstr_discrete res *
  page181_i137
#ISCELL
  mstr_standard offpage *
  page181_i14
#ISCELL
  mstr_standard offpage *
  page181_i15
#ISCELL
  mstr_standard offpage *
  page181_i16
#ISCELL
  mstr_standard offpage *
  page181_i17
#ISCELL
  mstr_standard offpage *
  page181_i18
#ISCELL
  mstr_standard offpage *
  page181_i19
#ISCELL
  mstr_standard offpage *
  page181_i20
#ISCELL
  mstr_symbols p12v_psu *
  page181_i21
#CELL
  mstr_discrete res *
  page181_i22
#ISCELL
  mstr_standard offpage *
  page181_i23
#ISCELL
  mstr_standard offpage *
  page181_i24
#ISCELL
  mstr_standard offpage *
  page181_i25
#CELL
  mstr_discrete res *
  page181_i26
#CELL
  mstr_discrete res *
  page181_i27
#CELL
  mstr_discrete res *
  page181_i28
#CELL
  mstr_discrete res *
  page181_i29
#CELL
  mstr_discrete res *
  page181_i30
#CELL
  mstr_discrete res *
  page181_i31
#CELL
  mstr_discrete res *
  page181_i32
#CELL
  mstr_discrete res *
  page181_i33
#CELL
  dev_discrete cap_a *
  page181_i34
#ISCELL
  mstr_symbols gnd *
  page181_i35
#ISCELL
  mstr_symbols p3v3_stby *
  page181_i36
#CELL
  mstr_discrete diode *
  page181_i37
#ISCELL
  mstr_standard offpage *
  page181_i38
#ISCELL
  mstr_symbols gnd *
  page181_i39
#CELL
  mstr_discrete res *
  page181_i4
#CELL
  mstr_discrete cap *
  page181_i40
#ISCELL
  mstr_standard offpage *
  page181_i41
#CELL
  mstr_discrete npn *
  page181_i42
#ISCELL
  mstr_symbols gnd *
  page181_i43
#ISCELL
  mstr_standard tap *
  page181_i44
#ISCELL
  mstr_standard tap *
  page181_i45
#ISCELL
  mstr_standard tap *
  page181_i46
#ISCELL
  mstr_standard tap *
  page181_i47
#ISCELL
  mstr_standard tap *
  page181_i48
#ISCELL
  mstr_standard tap *
  page181_i49
#CELL
  mstr_discrete diode *
  page181_i5
#ISCELL
  mstr_standard tap *
  page181_i50
#ISCELL
  mstr_standard offpage *
  page181_i51
#ISCELL
  mstr_standard tap *
  page181_i52
#ISCELL
  mstr_standard tap *
  page181_i53
#ISCELL
  mstr_standard tap *
  page181_i54
#ISCELL
  mstr_standard tap *
  page181_i55
#ISCELL
  mstr_standard tap *
  page181_i56
#ISCELL
  mstr_standard tap *
  page181_i57
#ISCELL
  mstr_standard tap *
  page181_i58
#ISCELL
  mstr_standard tap *
  page181_i59
#ISCELL
  mstr_standard offpage *
  page181_i6
#CELL
  mstr_ttl ttl08 *
  page181_i60
#ISCELL
  mstr_symbols gnd *
  page181_i61
#ISCELL
  mstr_symbols gnd *
  page181_i62
#CELL
  mstr_discrete res *
  page181_i63
#CELL
  mstr_discrete res *
  page181_i64
#ISCELL
  mstr_standard offpage *
  page181_i65
#ISCELL
  mstr_standard offpage *
  page181_i66
#ISCELL
  mstr_symbols gnd *
  page181_i67
#CELL
  mstr_discrete res *
  page181_i68
#ISCELL
  mstr_symbols p12v_psu *
  page181_i69
#ISCELL
  mstr_standard offpage *
  page181_i7
#CELL
  mstr_discrete cap *
  page181_i70
#CELL
  mstr_discrete cap *
  page181_i71
#CELL
  mstr_discrete cap *
  page181_i72
#CELL
  mstr_discrete cap *
  page181_i73
#CELL
  mstr_discrete cap *
  page181_i74
#CELL
  mstr_discrete cap *
  page181_i75
#CELL
  mstr_discrete cap *
  page181_i76
#CELL
  mstr_discrete cap *
  page181_i77
#CELL
  mstr_discrete cap *
  page181_i78
#CELL
  mstr_discrete cap *
  page181_i79
#ISCELL
  mstr_standard offpage *
  page181_i8
#CELL
  mstr_discrete res *
  page181_i80
#CELL
  mstr_discrete res *
  page181_i81
#CELL
  mstr_discrete res *
  page181_i82
#ISCELL
  mstr_symbols p3v3_stby *
  page181_i83
#ISCELL
  mstr_standard tap *
  page181_i84
#ISCELL
  mstr_standard tap *
  page181_i85
#CELL
  mstr_discrete cap *
  page181_i86
#CELL
  mstr_discrete cap *
  page181_i87
#CELL
  mstr_discrete cap *
  page181_i88
#CELL
  mstr_discrete cap *
  page181_i89
#ISCELL
  mstr_standard offpage *
  page181_i9
#CELL
  mstr_discrete cap *
  page181_i90
#CELL
  mstr_discrete cap *
  page181_i91
#ISCELL
  mstr_standard tap *
  page181_i92
#ISCELL
  mstr_standard tap *
  page181_i93
#ISCELL
  mstr_standard tap *
  page181_i94
#ISCELL
  mstr_standard tap *
  page181_i95
#ISCELL
  mstr_standard tap *
  page181_i96
#ISCELL
  mstr_standard tap *
  page181_i97
#ISCELL
  mstr_standard offpage *
  page181_i98
#ISCELL
  mstr_standard offpage *
  page181_i99
